(kicad_pcb
	(version 20241229)
	(generator "pcbnew")
	(generator_version "9.0")
	(general
		(thickness 1.6)
		(legacy_teardrops no)
	)
	(paper "A4")
	(title_block
		(title "LPDDR4 testbed")
		(date "2024-03-26")
		(rev "1.2.2")
		(comment 9 "footprints 30-34 of 66")
	)
	(layers
		(0 "F.Cu" signal)
		(4 "In1.Cu" power)
		(6 "In2.Cu" power)
		(8 "In3.Cu" signal)
		(10 "In4.Cu" signal)
		(2 "B.Cu" signal)
		(9 "F.Adhes" user "F.Adhesive")
		(11 "B.Adhes" user "B.Adhesive")
		(13 "F.Paste" user)
		(15 "B.Paste" user)
		(5 "F.SilkS" user "F.Silkscreen")
		(7 "B.SilkS" user "B.Silkscreen")
		(1 "F.Mask" user)
		(3 "B.Mask" user)
		(17 "Dwgs.User" user "User.Drawings")
		(19 "Cmts.User" user "User.Comments")
		(21 "Eco1.User" user "User.Eco1")
		(23 "Eco2.User" user "User.Eco2")
		(25 "Edge.Cuts" user)
		(27 "Margin" user)
		(31 "F.CrtYd" user "F.Courtyard")
		(29 "B.CrtYd" user "B.Courtyard")
		(35 "F.Fab" user)
		(33 "B.Fab" user)
	)
	(footprint "antmicro-footprints:LED_0603_1608Metric_G"
		(layer "F.Cu")
		(at 131.258332 72.9 90)
		(descr "LED SMD 0603 Green")
		(tags "LED SMD 0603 Green")
		(property "Reference" "D3"
			(at 1.25 0.32 90)
			(layer "F.SilkS")
			(effects
				(font
					(size 0.7 0.7)
					(thickness 0.15)
				)
				(justify left bottom)
			)
		)
		(property "Value" "LED_G_0603_KP-1608CGCK"
			(at 0 1.6 90)
			(layer "F.Fab")
			(effects
				(font
					(size 0.7 0.7)
					(thickness 0.15)
				)
				(justify left bottom)
			)
		)
		(property "Author" "Antmicro"
			(at 204.158332 -58.358332 0)
			(layer "F.Fab")
			(hide yes)
			(effects
				(font
					(size 1 1)
					(thickness 0.15)
				)
			)
		)
		(property "License" "Apache-2.0"
			(at 204.158332 -58.358332 0)
			(layer "F.Fab")
			(hide yes)
			(effects
				(font
					(size 1 1)
					(thickness 0.15)
				)
			)
		)
		(property "MPN" "KP-1608CGCK"
			(at 204.158332 -58.358332 0)
			(layer "F.Fab")
			(hide yes)
			(effects
				(font
					(size 1 1)
					(thickness 0.15)
				)
			)
		)
		(property "Manufacturer" "Kingbright"
			(at 204.158332 -58.358332 0)
			(layer "F.Fab")
			(hide yes)
			(effects
				(font
					(size 1 1)
					(thickness 0.15)
				)
			)
		)
		(sheetname "EEPROM")
		(sheetfile "EEPROM.kicad_sch")
		(attr smd)
		(fp_line
			(start -0.27 -0.35)
			(end 0.27 -0.35)
			(stroke
				(width 0.15)
				(type solid)
			)
			(layer "F.SilkS")
		)
		(fp_line
			(start 0.093672 -0.200008)
			(end 0.093672 0.199992)
			(stroke
				(width 0.1)
				(type solid)
			)
			(layer "F.SilkS")
		)
		(fp_line
			(start -0.106328 -0.200008)
			(end 0.093672 -8e-06)
			(stroke
				(width 0.1)
				(type solid)
			)
			(layer "F.SilkS")
		)
		(fp_line
			(start -0.106328 -0.200008)
			(end -0.106328 0.199992)
			(stroke
				(width 0.1)
				(type solid)
			)
			(layer "F.SilkS")
		)
		(fp_line
			(start 0.093672 -8e-06)
			(end 0.293672 -8e-06)
			(stroke
				(width 0.1)
				(type solid)
			)
			(layer "F.SilkS")
		)
		(fp_line
			(start 0.093672 -8e-06)
			(end -0.106328 0.199992)
			(stroke
				(width 0.1)
				(type solid)
			)
			(layer "F.SilkS")
		)
		(fp_line
			(start -0.106328 -8e-06)
			(end -0.29 0)
			(stroke
				(width 0.1)
				(type solid)
			)
			(layer "F.SilkS")
		)
		(fp_line
			(start 1.25 0.32)
			(end 1.25 -0.32)
			(stroke
				(width 0.15)
				(type solid)
			)
			(layer "F.SilkS")
		)
		(fp_line
			(start -0.27 0.351)
			(end 0.27 0.351)
			(stroke
				(width 0.15)
				(type solid)
			)
			(layer "F.SilkS")
		)
		(fp_rect
			(start 1.26 0.65)
			(end -1.26 -0.65)
			(stroke
				(width 0.05)
				(type solid)
			)
			(fill no)
			(layer "F.CrtYd")
		)
		(fp_line
			(start 0.199 -0.2)
			(end 0.199 -0.1)
			(stroke
				(width 0.15)
				(type solid)
			)
			(layer "F.Fab")
		)
		(fp_line
			(start -0.201 -0.2)
			(end -0.201 0)
			(stroke
				(width 0.15)
				(type solid)
			)
			(layer "F.Fab")
		)
		(fp_line
			(start 0.199 0)
			(end 0.597 0)
			(stroke
				(width 0.15)
				(type solid)
			)
			(layer "F.Fab")
		)
		(fp_line
			(start 0.101 0)
			(end -0.201 -0.2)
			(stroke
				(width 0.15)
				(type solid)
			)
			(layer "F.Fab")
		)
		(fp_line
			(start -0.201 0)
			(end -0.201 0.202)
			(stroke
				(width 0.15)
				(type solid)
			)
			(layer "F.Fab")
		)
		(fp_line
			(start -0.599 0)
			(end -0.201 0)
			(stroke
				(width 0.15)
				(type solid)
			)
			(layer "F.Fab")
		)
		(fp_line
			(start 0.199 0.202)
			(end 0.199 -0.1)
			(stroke
				(width 0.15)
				(type solid)
			)
			(layer "F.Fab")
		)
		(fp_line
			(start -0.201 0.202)
			(end 0.101 0)
			(stroke
				(width 0.15)
				(type solid)
			)
			(layer "F.Fab")
		)
		(fp_rect
			(start -0.848 -0.4)
			(end 0.85 0.402)
			(stroke
				(width 0.15)
				(type solid)
			)
			(fill no)
			(layer "F.Fab")
		)
		(pad "1" smd rect
			(at -0.75 0 270)
			(size 0.8 0.8)
			(layers "F.Cu" "F.Mask" "F.Paste")
			(net 257 "Net-(D3-Pad1)")
			(pinfunction "1")
			(pintype "passive")
		)
		(pad "2" smd rect
			(at 0.75 0 270)
			(size 0.8 0.8)
			(layers "F.Cu" "F.Mask" "F.Paste")
			(net 36 "GND")
			(pinfunction "2")
			(pintype "passive")
		)
	)
	(footprint "antmicro-footprints:LED_0603_1608Metric_G"
		(layer "F.Cu")
		(at 127.625 72.9 90)
		(descr "LED SMD 0603 Green")
		(tags "LED SMD 0603 Green")
		(property "Reference" "D1"
			(at 1.25 0.32 90)
			(layer "F.SilkS")
			(effects
				(font
					(size 0.7 0.7)
					(thickness 0.15)
				)
				(justify left bottom)
			)
		)
		(property "Value" "LED_G_0603_KP-1608CGCK"
			(at 0 1.6 90)
			(layer "F.Fab")
			(effects
				(font
					(size 0.7 0.7)
					(thickness 0.15)
				)
				(justify left bottom)
			)
		)
		(property "Author" "Antmicro"
			(at 200.525 -54.725 0)
			(layer "F.Fab")
			(hide yes)
			(effects
				(font
					(size 1 1)
					(thickness 0.15)
				)
			)
		)
		(property "License" "Apache-2.0"
			(at 200.525 -54.725 0)
			(layer "F.Fab")
			(hide yes)
			(effects
				(font
					(size 1 1)
					(thickness 0.15)
				)
			)
		)
		(property "MPN" "KP-1608CGCK"
			(at 200.525 -54.725 0)
			(layer "F.Fab")
			(hide yes)
			(effects
				(font
					(size 1 1)
					(thickness 0.15)
				)
			)
		)
		(property "Manufacturer" "Kingbright"
			(at 200.525 -54.725 0)
			(layer "F.Fab")
			(hide yes)
			(effects
				(font
					(size 1 1)
					(thickness 0.15)
				)
			)
		)
		(sheetname "EEPROM")
		(sheetfile "EEPROM.kicad_sch")
		(attr smd)
		(fp_line
			(start -0.27 -0.35)
			(end 0.27 -0.35)
			(stroke
				(width 0.15)
				(type solid)
			)
			(layer "F.SilkS")
		)
		(fp_line
			(start 0.093672 -0.200008)
			(end 0.093672 0.199992)
			(stroke
				(width 0.1)
				(type solid)
			)
			(layer "F.SilkS")
		)
		(fp_line
			(start -0.106328 -0.200008)
			(end 0.093672 -8e-06)
			(stroke
				(width 0.1)
				(type solid)
			)
			(layer "F.SilkS")
		)
		(fp_line
			(start -0.106328 -0.200008)
			(end -0.106328 0.199992)
			(stroke
				(width 0.1)
				(type solid)
			)
			(layer "F.SilkS")
		)
		(fp_line
			(start 0.093672 -8e-06)
			(end 0.293672 -8e-06)
			(stroke
				(width 0.1)
				(type solid)
			)
			(layer "F.SilkS")
		)
		(fp_line
			(start 0.093672 -8e-06)
			(end -0.106328 0.199992)
			(stroke
				(width 0.1)
				(type solid)
			)
			(layer "F.SilkS")
		)
		(fp_line
			(start -0.106328 -8e-06)
			(end -0.29 0)
			(stroke
				(width 0.1)
				(type solid)
			)
			(layer "F.SilkS")
		)
		(fp_line
			(start 1.25 0.32)
			(end 1.25 -0.32)
			(stroke
				(width 0.15)
				(type solid)
			)
			(layer "F.SilkS")
		)
		(fp_line
			(start -0.27 0.351)
			(end 0.27 0.351)
			(stroke
				(width 0.15)
				(type solid)
			)
			(layer "F.SilkS")
		)
		(fp_rect
			(start 1.26 0.65)
			(end -1.26 -0.65)
			(stroke
				(width 0.05)
				(type solid)
			)
			(fill no)
			(layer "F.CrtYd")
		)
		(fp_line
			(start 0.199 -0.2)
			(end 0.199 -0.1)
			(stroke
				(width 0.15)
				(type solid)
			)
			(layer "F.Fab")
		)
		(fp_line
			(start -0.201 -0.2)
			(end -0.201 0)
			(stroke
				(width 0.15)
				(type solid)
			)
			(layer "F.Fab")
		)
		(fp_line
			(start 0.199 0)
			(end 0.597 0)
			(stroke
				(width 0.15)
				(type solid)
			)
			(layer "F.Fab")
		)
		(fp_line
			(start 0.101 0)
			(end -0.201 -0.2)
			(stroke
				(width 0.15)
				(type solid)
			)
			(layer "F.Fab")
		)
		(fp_line
			(start -0.201 0)
			(end -0.201 0.202)
			(stroke
				(width 0.15)
				(type solid)
			)
			(layer "F.Fab")
		)
		(fp_line
			(start -0.599 0)
			(end -0.201 0)
			(stroke
				(width 0.15)
				(type solid)
			)
			(layer "F.Fab")
		)
		(fp_line
			(start 0.199 0.202)
			(end 0.199 -0.1)
			(stroke
				(width 0.15)
				(type solid)
			)
			(layer "F.Fab")
		)
		(fp_line
			(start -0.201 0.202)
			(end 0.101 0)
			(stroke
				(width 0.15)
				(type solid)
			)
			(layer "F.Fab")
		)
		(fp_rect
			(start -0.848 -0.4)
			(end 0.85 0.402)
			(stroke
				(width 0.15)
				(type solid)
			)
			(fill no)
			(layer "F.Fab")
		)
		(pad "1" smd rect
			(at -0.75 0 270)
			(size 0.8 0.8)
			(layers "F.Cu" "F.Mask" "F.Paste")
			(net 255 "Net-(D1-Pad1)")
			(pinfunction "1")
			(pintype "passive")
		)
		(pad "2" smd rect
			(at 0.75 0 270)
			(size 0.8 0.8)
			(layers "F.Cu" "F.Mask" "F.Paste")
			(net 36 "GND")
			(pinfunction "2")
			(pintype "passive")
		)
	)
	(footprint "antmicro-footprints:SOT-23-5"
		(layer "F.Cu")
		(at 129.365 91.13)
		(property "Reference" "IC2"
			(at -0.99 2.82 0)
			(layer "F.SilkS")
			(effects
				(font
					(size 0.7 0.7)
					(thickness 0.15)
				)
				(justify left bottom)
			)
		)
		(property "Value" "AT24CS01_SOT23"
			(at 0.002 2.799 0)
			(layer "F.Fab")
			(effects
				(font
					(size 0.7 0.7)
					(thickness 0.15)
				)
				(justify left bottom)
			)
		)
		(property "Description" "SOT-23-5"
			(at 0 0 0)
			(layer "F.Fab")
			(hide yes)
			(effects
				(font
					(size 1.27 1.27)
					(thickness 0.15)
				)
			)
		)
		(property "Author" "Antmicro"
			(at 0 0 0)
			(layer "F.Fab")
			(hide yes)
			(effects
				(font
					(size 1 1)
					(thickness 0.15)
				)
			)
		)
		(property "License" "Apache-2.0"
			(at 0 0 0)
			(layer "F.Fab")
			(hide yes)
			(effects
				(font
					(size 1 1)
					(thickness 0.15)
				)
			)
		)
		(property "MPN" "AT24CS01-ST"
			(at 0 0 0)
			(layer "F.Fab")
			(hide yes)
			(effects
				(font
					(size 1 1)
					(thickness 0.15)
				)
			)
		)
		(property "Manufacturer" "Atmel"
			(at 0 0 0)
			(layer "F.Fab")
			(hide yes)
			(effects
				(font
					(size 1 1)
					(thickness 0.15)
				)
			)
		)
		(sheetname "EEPROM")
		(sheetfile "EEPROM.kicad_sch")
		(attr smd)
		(fp_line
			(start -0.85 1.6)
			(end -0.85 1.301)
			(stroke
				(width 0.15)
				(type solid)
			)
			(layer "F.SilkS")
		)
		(fp_line
			(start -0.8 -1.6)
			(end -0.8 -1.3)
			(stroke
				(width 0.15)
				(type solid)
			)
			(layer "F.SilkS")
		)
		(fp_line
			(start -0.8 -1.6)
			(end -0.5 -1.6)
			(stroke
				(width 0.15)
				(type solid)
			)
			(layer "F.SilkS")
		)
		(fp_line
			(start -0.55 1.6)
			(end -0.85 1.6)
			(stroke
				(width 0.15)
				(type solid)
			)
			(layer "F.SilkS")
		)
		(fp_line
			(start 0.8 -1.6)
			(end 0.5 -1.6)
			(stroke
				(width 0.15)
				(type solid)
			)
			(layer "F.SilkS")
		)
		(fp_line
			(start 0.8 -1.3)
			(end 0.8 -1.6)
			(stroke
				(width 0.15)
				(type solid)
			)
			(layer "F.SilkS")
		)
		(fp_line
			(start 0.8 0.55)
			(end 0.8 -0.55)
			(stroke
				(width 0.15)
				(type solid)
			)
			(layer "F.SilkS")
		)
		(fp_line
			(start 0.8 1.3)
			(end 0.8 1.599)
			(stroke
				(width 0.15)
				(type solid)
			)
			(layer "F.SilkS")
		)
		(fp_line
			(start 0.8 1.599)
			(end 0.549 1.599)
			(stroke
				(width 0.15)
				(type solid)
			)
			(layer "F.SilkS")
		)
		(fp_circle
			(center -1.25 -1.5)
			(end -1.2 -1.5)
			(stroke
				(width 0.15)
				(type solid)
			)
			(fill yes)
			(layer "F.SilkS")
		)
		(fp_rect
			(start 1.9 -1.76)
			(end -1.9 1.75)
			(stroke
				(width 0.05)
				(type solid)
			)
			(fill no)
			(layer "F.CrtYd")
		)
		(fp_line
			(start -0.398 -1.526)
			(end -0.874 -1.05)
			(stroke
				(width 0.15)
				(type solid)
			)
			(layer "F.Fab")
		)
		(fp_rect
			(start 0.874 1.523)
			(end -0.873 -1.525)
			(stroke
				(width 0.15)
				(type solid)
			)
			(fill no)
			(layer "F.Fab")
		)
		(pad "1" smd rect
			(at -1.351 -0.951 270)
			(size 0.55 1)
			(layers "F.Cu" "F.Mask" "F.Paste")
			(net 247 "SCL")
			(pinfunction "SCL")
			(pintype "passive")
		)
		(pad "2" smd rect
			(at -1.351 0 270)
			(size 0.55 1)
			(layers "F.Cu" "F.Mask" "F.Paste")
			(net 36 "GND")
			(pinfunction "GND")
			(pintype "passive")
		)
		(pad "3" smd rect
			(at -1.351 0.949 270)
			(size 0.55 1)
			(layers "F.Cu" "F.Mask" "F.Paste")
			(net 246 "SDA")
			(pinfunction "SDA")
			(pintype "passive")
		)
		(pad "4" smd rect
			(at 1.35 0.949 270)
			(size 0.55 1)
			(layers "F.Cu" "F.Mask" "F.Paste")
			(net 187 "VDD1")
			(pinfunction "VCC")
			(pintype "passive")
		)
		(pad "5" smd rect
			(at 1.35 -0.951 270)
			(size 0.55 1)
			(layers "F.Cu" "F.Mask" "F.Paste")
			(net 36 "GND")
			(pinfunction "WP")
			(pintype "passive")
		)
	)
	(footprint "lpddr4-testbed-footprints:L_0806_2016Metric"
		(layer "F.Cu")
		(at 131.725 86.45 180)
		(property "Reference" "L1"
			(at 0 -1.2 180)
			(layer "F.SilkS")
			(effects
				(font
					(size 0.7 0.7)
					(thickness 0.15)
				)
				(justify left bottom)
			)
		)
		(property "Value" "L_2u2_1.5A_1285AS-H"
			(at 0 2 180)
			(layer "F.Fab")
			(effects
				(font
					(size 0.7 0.7)
					(thickness 0.15)
				)
				(justify left bottom)
			)
		)
		(property "Author" "Antmicro"
			(at 263.45 172.9 0)
			(layer "F.Fab")
			(hide yes)
			(effects
				(font
					(size 1 1)
					(thickness 0.15)
				)
			)
		)
		(property "IMax" ""
			(at 263.45 172.9 0)
			(layer "F.Fab")
			(hide yes)
			(effects
				(font
					(size 1 1)
					(thickness 0.15)
				)
			)
		)
		(property "ISat" ""
			(at 263.45 172.9 0)
			(layer "F.Fab")
			(hide yes)
			(effects
				(font
					(size 1 1)
					(thickness 0.15)
				)
			)
		)
		(property "Imax" "1.5A"
			(at 263.45 172.9 0)
			(layer "F.Fab")
			(hide yes)
			(effects
				(font
					(size 1 1)
					(thickness 0.15)
				)
			)
		)
		(property "Isat" "1.2A"
			(at 263.45 172.9 0)
			(layer "F.Fab")
			(hide yes)
			(effects
				(font
					(size 1 1)
					(thickness 0.15)
				)
			)
		)
		(property "License" "Apache-2.0"
			(at 263.45 172.9 0)
			(layer "F.Fab")
			(hide yes)
			(effects
				(font
					(size 1 1)
					(thickness 0.15)
				)
			)
		)
		(property "MPN" "1285AS-H-2R2M=P2"
			(at 263.45 172.9 0)
			(layer "F.Fab")
			(hide yes)
			(effects
				(font
					(size 1 1)
					(thickness 0.15)
				)
			)
		)
		(property "Manufacturer" "Murata"
			(at 263.45 172.9 0)
			(layer "F.Fab")
			(hide yes)
			(effects
				(font
					(size 1 1)
					(thickness 0.15)
				)
			)
		)
		(property "Size" "0806_2016Metric"
			(at 263.45 172.9 0)
			(layer "F.Fab")
			(hide yes)
			(effects
				(font
					(size 1 1)
					(thickness 0.15)
				)
			)
		)
		(property "Val" "2u2/1.5A"
			(at 263.45 172.9 0)
			(layer "F.Fab")
			(hide yes)
			(effects
				(font
					(size 1 1)
					(thickness 0.15)
				)
			)
		)
		(sheetname "EEPROM")
		(sheetfile "EEPROM.kicad_sch")
		(attr smd)
		(fp_line
			(start -0.3 -0.9)
			(end 0.298 -0.9)
			(stroke
				(width 0.15)
				(type solid)
			)
			(layer "F.SilkS")
		)
		(fp_line
			(start -0.301 0.9)
			(end 0.299 0.9)
			(stroke
				(width 0.15)
				(type solid)
			)
			(layer "F.SilkS")
		)
		(fp_rect
			(start -1.75 -1.05)
			(end 1.75 1.05)
			(stroke
				(width 0.05)
				(type solid)
			)
			(fill no)
			(layer "F.CrtYd")
		)
		(fp_rect
			(start -0.951 -0.882)
			(end 0.949 0.875)
			(stroke
				(width 0.15)
				(type solid)
			)
			(fill no)
			(layer "F.Fab")
		)
		(pad "1" smd roundrect
			(at -1.1 -0.001 180)
			(size 1 1.8)
			(layers "F.Cu" "F.Mask" "F.Paste")
			(roundrect_rratio 0.15)
			(net 187 "VDD1")
			(pintype "passive")
		)
		(pad "2" smd roundrect
			(at 1.1 -0.001 180)
			(size 1 1.8)
			(layers "F.Cu" "F.Mask" "F.Paste")
			(roundrect_rratio 0.15)
			(net 157 "Net-(U2-SW)")
			(pintype "passive")
		)
	)
	(footprint "antmicro-footprints:R_0402_1005Metric"
		(layer "F.Cu")
		(at 128.53 81.145 180)
		(descr "Resistor SMD 0402")
		(tags "resistor SMD 0402")
		(property "Reference" "R8"
			(at 0.755 0.595 180)
			(layer "F.SilkS")
			(effects
				(font
					(size 0.7 0.7)
					(thickness 0.15)
				)
				(justify left bottom)
			)
		)
		(property "Value" "R_0R_0402"
			(at 0 1.4 180)
			(layer "F.Fab")
			(effects
				(font
					(size 0.7 0.7)
					(thickness 0.15)
				)
				(justify left bottom)
			)
		)
		(property "Description" "0R resistor in 0402 package with unspecified tolerance"
			(at 0 0 180)
			(layer "F.Fab")
			(hide yes)
			(effects
				(font
					(size 1.27 1.27)
					(thickness 0.15)
				)
			)
		)
		(property "Author" "Antmicro"
			(at 257.06 162.29 0)
			(layer "F.Fab")
			(hide yes)
			(effects
				(font
					(size 1 1)
					(thickness 0.15)
				)
			)
		)
		(property "Current" "1A"
			(at 257.06 162.29 0)
			(layer "F.Fab")
			(hide yes)
			(effects
				(font
					(size 1 1)
					(thickness 0.15)
				)
			)
		)
		(property "License" "Apache-2.0"
			(at 257.06 162.29 0)
			(layer "F.Fab")
			(hide yes)
			(effects
				(font
					(size 1 1)
					(thickness 0.15)
				)
			)
		)
		(property "MPN" "ERJ2GE0R00X"
			(at 257.06 162.29 0)
			(layer "F.Fab")
			(hide yes)
			(effects
				(font
					(size 1 1)
					(thickness 0.15)
				)
			)
		)
		(property "Manufacturer" "Panasonic"
			(at 257.06 162.29 0)
			(layer "F.Fab")
			(hide yes)
			(effects
				(font
					(size 1 1)
					(thickness 0.15)
				)
			)
		)
		(property "Tolerance" ""
			(at 257.06 162.29 0)
			(layer "F.Fab")
			(hide yes)
			(effects
				(font
					(size 1 1)
					(thickness 0.15)
				)
			)
		)
		(property "Val" "0R"
			(at 257.06 162.29 0)
			(layer "F.Fab")
			(hide yes)
			(effects
				(font
					(size 1 1)
					(thickness 0.15)
				)
			)
		)
		(sheetname "EEPROM")
		(sheetfile "EEPROM.kicad_sch")
		(attr exclude_from_pos_files exclude_from_bom dnp)
		(fp_rect
			(start -0.93 -0.47)
			(end 0.93 0.47)
			(stroke
				(width 0.05)
				(type solid)
			)
			(fill no)
			(layer "F.CrtYd")
		)
		(fp_rect
			(start -0.5 -0.25)
			(end 0.5 0.25)
			(stroke
				(width 0.15)
				(type solid)
			)
			(fill no)
			(layer "F.Fab")
		)
		(pad "1" smd roundrect
			(at -0.485 0 180)
			(size 0.59 0.64)
			(layers "F.Cu" "F.Mask" "F.Paste")
			(roundrect_rratio 0.25)
			(net 187 "VDD1")
			(pintype "passive")
		)
		(pad "2" smd roundrect
			(at 0.485 0 180)
			(size 0.59 0.64)
			(layers "F.Cu" "F.Mask" "F.Paste")
			(roundrect_rratio 0.25)
			(net 241 "VDDLED")
			(pintype "passive")
		)
	)
)
